FILE_TYPE=LIBRARY_PARTS;
primitive 'RT9059','RT9059_DFN';
  pin
    'ADJ_NC':
      PIN_NUMBER='(4)';
      OUTPUT_LOAD='(1.0,-1.0)';
    'EN':
      PIN_NUMBER='(6)';
      INPUT_LOAD='(-0.01,0.01)';
    'GND':
      PIN_NUMBER='(11)';
      PINUSE='GROUND';
      NO_LOAD_CHECK='Both';
      NO_IO_CHECK='Both';
      NO_ASSERT_CHECK='TRUE';
      NO_DIR_CHECK='TRUE';
      ALLOW_CONNECT='TRUE';
    'PGOOD':
      PIN_NUMBER='(5)';
      OUTPUT_LOAD='(1.0,-1.0)';
    'VDD':
      PIN_NUMBER='(10)';
      PINUSE='POWER';
      NO_LOAD_CHECK='Both';
      NO_IO_CHECK='Both';
      NO_ASSERT_CHECK='TRUE';
      NO_DIR_CHECK='TRUE';
      ALLOW_CONNECT='TRUE';
    'VIN'<2>:
      PIN_NUMBER='(9)';
      INPUT_LOAD='(-0.01,0.01)';
    'VIN'<1>:
      PIN_NUMBER='(8)';
      INPUT_LOAD='(-0.01,0.01)';
    'VIN'<0>:
      PIN_NUMBER='(7)';
      INPUT_LOAD='(-0.01,0.01)';
    'VOUT'<2>:
      PIN_NUMBER='(3)';
      OUTPUT_LOAD='(1.0,-1.0)';
    'VOUT'<1>:
      PIN_NUMBER='(2)';
      OUTPUT_LOAD='(1.0,-1.0)';
    'VOUT'<0>:
      PIN_NUMBER='(1)';
      OUTPUT_LOAD='(1.0,-1.0)';
  end_pin;
  body
    PART_NAME='RT9059';
    PHYS_DES_PREFIX='EU';
  end_body;
end_primitive;

END.
